# S9S_MB_2U (Grand Teton) — schematic netlist excerpt (pin names and nets, part order shuffled) for the footprints in the layout excerpt that follows; sources: Cadence DE-HDL packaged netlist, KiCad conversion of 03242023_DA0F0TMBIJ0_F0T_Motherboard_J_brd_V01_OCP.brd

R2377  Q_RES  1K 1% CHIP  pkg 0402LF  page 266 : A = P3V3_AUX ; B = PWRGD_PVCCFA_EHV_FIVRA_CPU0_R
R253  Q_RES  240 1% CHIP  pkg 0402LF  page 120 : A = PVNN_TERM_CPU0 ; B = FM_S3M_CPU0_LVC1_GPIO_2

(kicad_pcb
	(version 20260206)
	(generator "pcbnew")
	(generator_version "10.0")
	(general
		(thickness 1.6)
		(legacy_teardrops no)
	)
	(paper "A4")
	(title_block
		(title "03242023_DA0F0TMBIJ0_F0T_Motherboard_J_brd_V01_OCP.brd")
		(comment 1 "Grand Teton / footprints 5050-5051 of 6105")
	)
	(layers
		(0 "F.Cu" signal "TOP")
		(4 "In1.Cu" signal "GND")
		(6 "In2.Cu" signal "IN1")
		(8 "In3.Cu" signal "GND1")
		(10 "In4.Cu" signal "IN2")
		(12 "In5.Cu" signal "GND2")
		(14 "In6.Cu" signal "IN3")
		(16 "In7.Cu" signal "GND3")
		(18 "In8.Cu" signal "VCC")
		(20 "In9.Cu" signal "VCC1")
		(22 "In10.Cu" signal "GND4")
		(24 "In11.Cu" signal "IN4")
		(26 "In12.Cu" signal "GND5")
		(28 "In13.Cu" signal "IN5")
		(30 "In14.Cu" signal "GND6")
		(32 "In15.Cu" signal "IN6")
		(34 "In16.Cu" signal "GND7")
		(2 "B.Cu" signal "BOTTOM")
		(9 "F.Adhes" user "F.Adhesive")
		(11 "B.Adhes" user "B.Adhesive")
		(13 "F.Paste" user "Package Geometry/Pastemask Top")
		(15 "B.Paste" user "Package Geometry/Pastemask Bottom")
		(5 "F.SilkS" user "Ref Des/Silkscreen Top")
		(7 "B.SilkS" user "Ref Des/Silkscreen Bottom")
		(1 "F.Mask" user "Board Geometry/Soldermask Top")
		(3 "B.Mask" user "Board Geometry/Soldermask Bottom")
		(17 "Dwgs.User" user "User.Drawings")
		(19 "Cmts.User" user "User.Comments")
		(21 "Eco1.User" user "User.Eco1")
		(23 "Eco2.User" user "User.Eco2")
		(25 "Edge.Cuts" user "Board Geometry/Outline")
		(27 "Margin" user)
		(31 "F.CrtYd" user "Package Geometry/Place Bound Top")
		(29 "B.CrtYd" user "Package Geometry/Place Bound Bottom")
		(35 "F.Fab" user "Ref Des/Assembly Top")
		(33 "B.Fab" user "Ref Des/Assembly Bottom")
	)
	(footprint ""
		(layer "B.Cu")
		(at 348.2467 -358.848914 180)
		(property "Reference" "R2377"
			(at 0 0 0)
			(layer "B.SilkS")
			(hide yes)
			(effects
				(font
					(size 1.27 1.27)
				)
				(justify mirror)
			)
		)
		(property "Value" ""
			(at 0 0 0)
			(layer "B.Fab")
			(effects
				(font
					(size 1.27 1.27)
				)
				(justify mirror)
			)
		)
		(duplicate_pad_numbers_are_jumpers no)
		(fp_line
			(start 0.7874 0.4064)
			(end 0.7874 -0.4064)
			(stroke
				(width 0.1524)
				(type default)
			)
			(layer "B.SilkS")
		)
		(fp_line
			(start 0.7874 -0.4064)
			(end -0.7874 -0.4064)
			(stroke
				(width 0.1524)
				(type default)
			)
			(layer "B.SilkS")
		)
		(fp_line
			(start -0.7874 0.4064)
			(end 0.7874 0.4064)
			(stroke
				(width 0.1524)
				(type default)
			)
			(layer "B.SilkS")
		)
		(fp_line
			(start -0.7874 -0.4064)
			(end -0.7874 0.4064)
			(stroke
				(width 0.1524)
				(type default)
			)
			(layer "B.SilkS")
		)
		(fp_line
			(start 0.67945 0.3048)
			(end 0.67945 -0.305054)
			(stroke
				(width 0.1)
				(type default)
			)
			(layer "B.Fab")
		)
		(fp_line
			(start 0.67945 -0.305054)
			(end 0.12065 -0.305054)
			(stroke
				(width 0.1)
				(type default)
			)
			(layer "B.Fab")
		)
		(fp_line
			(start 0.12065 0.3048)
			(end 0.67945 0.3048)
			(stroke
				(width 0.1)
				(type default)
			)
			(layer "B.Fab")
		)
		(fp_line
			(start 0.12065 0.2794)
			(end 0.12065 0.3048)
			(stroke
				(width 0.1)
				(type default)
			)
			(layer "B.Fab")
		)
		(fp_line
			(start 0.12065 -0.2794)
			(end -0.12065 -0.2794)
			(stroke
				(width 0.1)
				(type default)
			)
			(layer "B.Fab")
		)
		(fp_line
			(start 0.12065 -0.305054)
			(end 0.12065 -0.2794)
			(stroke
				(width 0.1)
				(type default)
			)
			(layer "B.Fab")
		)
		(fp_line
			(start -0.120396 0.3048)
			(end -0.120396 0.2794)
			(stroke
				(width 0.1)
				(type default)
			)
			(layer "B.Fab")
		)
		(fp_line
			(start -0.120396 0.2794)
			(end 0.12065 0.2794)
			(stroke
				(width 0.1)
				(type default)
			)
			(layer "B.Fab")
		)
		(fp_line
			(start -0.12065 -0.2794)
			(end -0.12065 -0.3048)
			(stroke
				(width 0.1)
				(type default)
			)
			(layer "B.Fab")
		)
		(fp_line
			(start -0.12065 -0.3048)
			(end -0.67945 -0.3048)
			(stroke
				(width 0.1)
				(type default)
			)
			(layer "B.Fab")
		)
		(fp_line
			(start -0.67945 0.3048)
			(end -0.120396 0.3048)
			(stroke
				(width 0.1)
				(type default)
			)
			(layer "B.Fab")
		)
		(fp_line
			(start -0.67945 -0.3048)
			(end -0.67945 0.3048)
			(stroke
				(width 0.1)
				(type default)
			)
			(layer "B.Fab")
		)
		(pad "1" smd circle
			(at 0.40005 0)
			(size 0 0)
			(layers "B.Cu" "B.Mask" "B.Paste")
			(net "P3V3_AUX")
		)
		(pad "2" smd circle
			(at -0.40005 0)
			(size 0 0)
			(layers "B.Cu" "B.Mask" "B.Paste")
			(net "PWRGD_PVCCFA_EHV_FIVRA_CPU0_R")
		)
	)
	(footprint ""
		(layer "B.Cu")
		(at 278.128984 -193.669666 -90)
		(property "Reference" "R253"
			(at 0 0 90)
			(layer "B.SilkS")
			(hide yes)
			(effects
				(font
					(size 1.27 1.27)
				)
				(justify mirror)
			)
		)
		(property "Value" ""
			(at 0 0 90)
			(layer "B.Fab")
			(effects
				(font
					(size 1.27 1.27)
				)
				(justify mirror)
			)
		)
		(duplicate_pad_numbers_are_jumpers no)
		(fp_line
			(start -0.7874 0.4064)
			(end 0.7874 0.4064)
			(stroke
				(width 0.1524)
				(type default)
			)
			(layer "B.SilkS")
		)
		(fp_line
			(start 0.7874 0.4064)
			(end 0.7874 -0.4064)
			(stroke
				(width 0.1524)
				(type default)
			)
			(layer "B.SilkS")
		)
		(fp_line
			(start -0.7874 -0.4064)
			(end -0.7874 0.4064)
			(stroke
				(width 0.1524)
				(type default)
			)
			(layer "B.SilkS")
		)
		(fp_line
			(start 0.7874 -0.4064)
			(end -0.7874 -0.4064)
			(stroke
				(width 0.1524)
				(type default)
			)
			(layer "B.SilkS")
		)
		(fp_line
			(start -0.67945 0.3048)
			(end -0.120396 0.3048)
			(stroke
				(width 0.1)
				(type default)
			)
			(layer "B.Fab")
		)
		(fp_line
			(start -0.120396 0.3048)
			(end -0.120396 0.2794)
			(stroke
				(width 0.1)
				(type default)
			)
			(layer "B.Fab")
		)
		(fp_line
			(start 0.12065 0.3048)
			(end 0.67945 0.3048)
			(stroke
				(width 0.1)
				(type default)
			)
			(layer "B.Fab")
		)
		(fp_line
			(start 0.67945 0.3048)
			(end 0.67945 -0.305054)
			(stroke
				(width 0.1)
				(type default)
			)
			(layer "B.Fab")
		)
		(fp_line
			(start -0.120396 0.2794)
			(end 0.12065 0.2794)
			(stroke
				(width 0.1)
				(type default)
			)
			(layer "B.Fab")
		)
		(fp_line
			(start 0.12065 0.2794)
			(end 0.12065 0.3048)
			(stroke
				(width 0.1)
				(type default)
			)
			(layer "B.Fab")
		)
		(fp_line
			(start -0.12065 -0.2794)
			(end -0.12065 -0.3048)
			(stroke
				(width 0.1)
				(type default)
			)
			(layer "B.Fab")
		)
		(fp_line
			(start 0.12065 -0.2794)
			(end -0.12065 -0.2794)
			(stroke
				(width 0.1)
				(type default)
			)
			(layer "B.Fab")
		)
		(fp_line
			(start -0.67945 -0.3048)
			(end -0.67945 0.3048)
			(stroke
				(width 0.1)
				(type default)
			)
			(layer "B.Fab")
		)
		(fp_line
			(start -0.12065 -0.3048)
			(end -0.67945 -0.3048)
			(stroke
				(width 0.1)
				(type default)
			)
			(layer "B.Fab")
		)
		(fp_line
			(start 0.12065 -0.305054)
			(end 0.12065 -0.2794)
			(stroke
				(width 0.1)
				(type default)
			)
			(layer "B.Fab")
		)
		(fp_line
			(start 0.67945 -0.305054)
			(end 0.12065 -0.305054)
			(stroke
				(width 0.1)
				(type default)
			)
			(layer "B.Fab")
		)
		(pad "1" smd circle
			(at 0.40005 0 90)
			(size 0 0)
			(layers "B.Cu" "B.Mask" "B.Paste")
			(net "PVNN_TERM_CPU0")
		)
		(pad "2" smd circle
			(at -0.40005 0 90)
			(size 0 0)
			(layers "B.Cu" "B.Mask" "B.Paste")
			(net "FM_S3M_CPU0_LVC1_GPIO_2")
		)
	)
)
